# TIMECARD (Time Appliance Project (Time Card)) — schematic netlist excerpt (pin names and nets, part order shuffled) for the footprints in the layout excerpt that follows; sources: Cadence DE-HDL packaged netlist, KiCad conversion of R4006-B0001-02_R01.brd

R203  RESISTOR  33OHM 1%  pkg SMC_0402R_H016  page 10 : \1\ = UNNAMED_127_MT25QL128ABA1ESESOP ; \2\ = FLASH_DQ0_MOSI
C293  CAPACITOR  0.22UF 25V 10%  pkg SMC_0402R_H022  page 31 : \1\ = UNNAMED_515_CAPACITOR_I128_1 ; \2\ = SG

(kicad_pcb
	(version 20260206)
	(generator "pcbnew")
	(generator_version "10.0")
	(general
		(thickness 1.6)
		(legacy_teardrops no)
	)
	(paper "A4")
	(title_block
		(title "timecard-production-celestica-r4006 — R4006-B0001-02_R01.brd")
		(comment 1 "Time Appliance Project (Time Card) / footprints 740-741 of 1113")
	)
	(layers
		(0 "F.Cu" signal "TOP")
		(4 "In1.Cu" signal "L02_GND1")
		(6 "In2.Cu" signal "L03_SIG1")
		(8 "In3.Cu" signal "L04_GND2")
		(10 "In4.Cu" signal "L05_VCC1")
		(12 "In5.Cu" signal "L06_VCC2")
		(14 "In6.Cu" signal "L07_GND3")
		(16 "In7.Cu" signal "L08_SIG2")
		(18 "In8.Cu" signal "L09_GND4")
		(2 "B.Cu" signal "BOTTOM")
		(9 "F.Adhes" user "F.Adhesive")
		(11 "B.Adhes" user "B.Adhesive")
		(13 "F.Paste" user "Package Geometry/Pastemask Top")
		(15 "B.Paste" user "Package Geometry/Pastemask Bottom")
		(5 "F.SilkS" user "Ref Des/Silkscreen Top")
		(7 "B.SilkS" user "Ref Des/Silkscreen Bottom")
		(1 "F.Mask" user "Board Geometry/Soldermask Top")
		(3 "B.Mask" user "Board Geometry/Soldermask Bottom")
		(17 "Dwgs.User" user "User.Drawings")
		(19 "Cmts.User" user "User.Comments")
		(21 "Eco1.User" user "User.Eco1")
		(23 "Eco2.User" user "User.Eco2")
		(25 "Edge.Cuts" user "Board Geometry/Outline")
		(27 "Margin" user)
		(31 "F.CrtYd" user "Package Geometry/Place Bound Top")
		(29 "B.CrtYd" user "Package Geometry/Place Bound Bottom")
		(35 "F.Fab" user "Ref Des/Assembly Top")
		(33 "B.Fab" user "Ref Des/Assembly Bottom")
	)
	(footprint ""
		(layer "B.Cu")
		(at 88.519 -86.741 180)
		(property "Reference" "R203"
			(at -0.254 5.80263 0)
			(unlocked yes)
			(layer "B.SilkS")
			(effects
				(font
					(size 0.7874 0.5842)
					(thickness 0.1524)
				)
				(justify mirror)
			)
		)
		(property "Value" "VAL*"
			(at -0.02032 2.13233 180)
			(unlocked yes)
			(layer "B.Fab")
			(hide yes)
			(effects
				(font
					(size 0.7874 0.5842)
					(thickness 0.1524)
				)
				(justify mirror)
			)
		)
		(property "Tolerance" "TOL*"
			(at -0.044704 3.05435 180)
			(unlocked yes)
			(layer "Cmts.User")
			(hide yes)
			(effects
				(font
					(size 0.7874 0.5842)
					(thickness 0.1524)
				)
				(justify mirror)
			)
		)
		(property "User Part Number" "PARTNUM*"
			(at -0.02032 4.024884 180)
			(unlocked yes)
			(layer "Cmts.User")
			(hide yes)
			(effects
				(font
					(size 0.7874 0.5842)
					(thickness 0.1524)
				)
				(justify mirror)
			)
		)
		(property "Device Type" "RESISTOR-G155-133R0-01,33OHM,1%"
			(at -0.008382 1.210564 180)
			(unlocked yes)
			(layer "B.Fab")
			(hide yes)
			(effects
				(font
					(size 0.7874 0.5842)
					(thickness 0.1524)
				)
				(justify mirror)
			)
		)
		(duplicate_pad_numbers_are_jumpers no)
		(fp_line
			(start 1.143 0.5588)
			(end -1.143 0.5588)
			(stroke
				(width 0.1)
				(type default)
			)
			(layer "B.SilkS")
		)
		(fp_line
			(start 1.143 -0.5588)
			(end 1.143 0.5588)
			(stroke
				(width 0.1)
				(type default)
			)
			(layer "B.SilkS")
		)
		(fp_line
			(start -1.143 0.5588)
			(end -1.143 -0.5588)
			(stroke
				(width 0.1)
				(type default)
			)
			(layer "B.SilkS")
		)
		(fp_line
			(start -1.143 -0.5588)
			(end 1.143 -0.5588)
			(stroke
				(width 0.1)
				(type default)
			)
			(layer "B.SilkS")
		)
		(fp_rect
			(start 1.143 -0.5588)
			(end -1.143 0.5588)
			(stroke
				(width 0)
				(type default)
			)
			(fill no)
			(layer "B.CrtYd")
		)
		(fp_line
			(start 0.508 0.3048)
			(end -0.508 0.3048)
			(stroke
				(width 0.1)
				(type default)
			)
			(layer "B.Fab")
		)
		(fp_line
			(start 0.508 -0.3048)
			(end 0.508 0.3048)
			(stroke
				(width 0.1)
				(type default)
			)
			(layer "B.Fab")
		)
		(fp_line
			(start -0.508 0.3048)
			(end -0.508 -0.3048)
			(stroke
				(width 0.1)
				(type default)
			)
			(layer "B.Fab")
		)
		(fp_line
			(start -0.508 -0.3048)
			(end 0.508 -0.3048)
			(stroke
				(width 0.1)
				(type default)
			)
			(layer "B.Fab")
		)
		(pad "1" smd rect
			(at 0.5334 0)
			(size 0.7112 0.6096)
			(layers "B.Cu" "B.Mask" "B.Paste")
			(net "UNNAMED_127_MT25QL128ABA1ESESOP")
		)
		(pad "2" smd rect
			(at -0.5334 0)
			(size 0.7112 0.6096)
			(layers "B.Cu" "B.Mask" "B.Paste")
			(net "FLASH_DQ0_MOSI")
		)
		(zone
			(layer "B.Cu")
			(hatch none 0.5)
			(connect_pads
				(clearance 0)
			)
			(min_thickness 0.25)
			(keepout
				(tracks allowed)
				(vias not_allowed)
				(pads allowed)
				(copperpour not_allowed)
				(footprints allowed)
			)
			(placement
				(enabled no)
				(sheetname "")
			)
			(fill
				(thermal_gap 0.5)
				(thermal_bridge_width 0.5)
				(island_removal_mode 0)
			)
			(polygon
				(pts
					(xy 88.4428 -86.4362) (xy 88.5952 -86.4362) (xy 88.5952 -87.0458) (xy 88.4428 -87.0458)
				)
			)
		)
	)
	(footprint ""
		(layer "B.Cu")
		(at 147.955 -19.685 -90)
		(property "Reference" "C293"
			(at -2.794 0.03937 270)
			(unlocked yes)
			(layer "B.SilkS")
			(effects
				(font
					(size 0.7874 0.5842)
					(thickness 0.1524)
				)
				(justify mirror)
			)
		)
		(property "Value" "VAL*"
			(at -0.0762 2.067306 270)
			(unlocked yes)
			(layer "B.Fab")
			(hide yes)
			(effects
				(font
					(size 0.7874 0.5842)
					(thickness 0.1524)
				)
				(justify mirror)
			)
		)
		(property "Tolerance" "TOL*"
			(at -0.0762 3.032506 270)
			(unlocked yes)
			(layer "Cmts.User")
			(hide yes)
			(effects
				(font
					(size 0.7874 0.5842)
					(thickness 0.1524)
				)
				(justify mirror)
			)
		)
		(property "User Part Number" "PARTNUM*"
			(at -0.1016 4.023106 270)
			(unlocked yes)
			(layer "Cmts.User")
			(hide yes)
			(effects
				(font
					(size 0.7874 0.5842)
					(thickness 0.1524)
				)
				(justify mirror)
			)
		)
		(property "Device Type" "CAPACITOR-G105-0B224-DK,0.22UFA"
			(at -0.0508 1.127506 270)
			(unlocked yes)
			(layer "B.Fab")
			(hide yes)
			(effects
				(font
					(size 0.7874 0.5842)
					(thickness 0.1524)
				)
				(justify mirror)
			)
		)
		(duplicate_pad_numbers_are_jumpers no)
		(fp_line
			(start -1.143 0.5588)
			(end -1.143 -0.5588)
			(stroke
				(width 0.1)
				(type default)
			)
			(layer "B.SilkS")
		)
		(fp_line
			(start 1.143 0.5588)
			(end -1.143 0.5588)
			(stroke
				(width 0.1)
				(type default)
			)
			(layer "B.SilkS")
		)
		(fp_line
			(start -1.143 -0.5588)
			(end 1.143 -0.5588)
			(stroke
				(width 0.1)
				(type default)
			)
			(layer "B.SilkS")
		)
		(fp_line
			(start 1.143 -0.5588)
			(end 1.143 0.5588)
			(stroke
				(width 0.1)
				(type default)
			)
			(layer "B.SilkS")
		)
		(fp_rect
			(start -1.143 0.5588)
			(end 1.143 -0.5588)
			(stroke
				(width 0)
				(type default)
			)
			(fill no)
			(layer "B.CrtYd")
		)
		(fp_line
			(start -0.508 0.3048)
			(end -0.508 -0.3048)
			(stroke
				(width 0.1)
				(type default)
			)
			(layer "B.Fab")
		)
		(fp_line
			(start 0.508 0.3048)
			(end -0.508 0.3048)
			(stroke
				(width 0.1)
				(type default)
			)
			(layer "B.Fab")
		)
		(fp_line
			(start -0.508 -0.3048)
			(end 0.508 -0.3048)
			(stroke
				(width 0.1)
				(type default)
			)
			(layer "B.Fab")
		)
		(fp_line
			(start 0.508 -0.3048)
			(end 0.508 0.3048)
			(stroke
				(width 0.1)
				(type default)
			)
			(layer "B.Fab")
		)
		(pad "1" smd rect
			(at 0.5334 0 90)
			(size 0.7112 0.6096)
			(layers "B.Cu" "B.Mask" "B.Paste")
			(net "UNNAMED_515_CAPACITOR_I128_1")
		)
		(pad "2" smd rect
			(at -0.5334 0 90)
			(size 0.7112 0.6096)
			(layers "B.Cu" "B.Mask" "B.Paste")
			(net "SG")
		)
		(zone
			(layer "B.Cu")
			(hatch none 0.5)
			(connect_pads
				(clearance 0)
			)
			(min_thickness 0.25)
			(keepout
				(tracks allowed)
				(vias not_allowed)
				(pads allowed)
				(copperpour not_allowed)
				(footprints allowed)
			)
			(placement
				(enabled no)
				(sheetname "")
			)
			(fill
				(thermal_gap 0.5)
				(thermal_bridge_width 0.5)
				(island_removal_mode 0)
			)
			(polygon
				(pts
					(xy 147.6502 -19.7612) (xy 147.6502 -19.6088) (xy 148.2598 -19.6088) (xy 148.2598 -19.7612)
				)
			)
		)
		(zone
			(layer "B.Cu")
			(hatch none 0.5)
			(connect_pads
				(clearance 0)
			)
			(min_thickness 0.25)
			(keepout
				(tracks not_allowed)
				(vias allowed)
				(pads allowed)
				(copperpour not_allowed)
				(footprints allowed)
			)
			(placement
				(enabled no)
				(sheetname "")
			)
			(fill
				(thermal_gap 0.5)
				(thermal_bridge_width 0.5)
				(island_removal_mode 0)
			)
			(polygon
				(pts
					(xy 147.6502 -19.7612) (xy 147.6502 -19.6088) (xy 148.2598 -19.6088) (xy 148.2598 -19.7612)
				)
			)
		)
	)
)
